FILE_TYPE = MACRO_DRAWING;
SET COLOR_WIRE YELLOW;
SET COLOR_PROP ORANGE;
SET COLOR_DOT WHITE;
SET COLOR_ARC YELLOW;
SET COLOR_BODY GREEN;
SET COLOR_NOTE PURPLE;
SET PROP_DISPLAY VALUE;
SET PAGE_NUMBER P80;
FORCEADD Q_RES..1
(-2375 -1225);
FORCEPROP 1 LAST PART_NUMBER CS21502FB07
J 0
(-2500 -1300);
DISPLAY 0.638298 (-2500 -1300);
DISPLAY INVISIBLE (-2500 -1300);
FORCEPROP 1 LAST PACK_TYPE 0402LF
J 0
(-2500 -1350);
DISPLAY 0.638298 (-2500 -1350);
FORCEPROP 1 LAST TOLERANCE 1%
J 0
(-2125 -1225);
DISPLAY 0.638298 (-2125 -1225);
FORCEPROP 1 LAST VALUE 1.5K
J 2
(-2150 -1225);
DISPLAY 0.638298 (-2150 -1225);
FORCEPROP 1 LAST MATERIAL CHIP
J 0
(-2000 -1225);
DISPLAY 0.638298 (-2000 -1225);
FORCEPROP 1 LAST WATTAGE 1/16W
J 2
(-2125 -1350);
DISPLAY 0.638298 (-2125 -1350);
FORCEPROP 1 LAST $LOCATION R1216
J 0
(-2625 -1225);
DISPLAY 0.787234 (-2625 -1225);
FORCEPROP 1 LASTPIN (-2475 -1225) $PN 1
J 0
(-2463 -1213);
DISPLAY 0.787234 (-2463 -1213);
PAINT MONO (-2463 -1213);
FORCEPROP 1 LASTPIN (-2275 -1225) $PN 2
J 0
(-2313 -1213);
DISPLAY 0.787234 (-2313 -1213);
PAINT MONO (-2313 -1213);
FORCEPROP 2 LAST CDS_LIB pure_quanta
J 0
(-2375 -1225);
DISPLAY INVISIBLE (-2375 -1225);
FORCEPROP 2 LAST CDS_LOCATION R1216
J 0
(-2425 -1025);
DISPLAY 1.021277 (-2425 -1025);
DISPLAY INVISIBLE (-2425 -1025);
FORCEPROP 0 LAST $SEC 1
J 0
(-2000 -1175);
DISPLAY 0.680851 (-2000 -1175);
PAINT MONO (-2000 -1175);
DISPLAY INVISIBLE (-2000 -1175);
FORCEPROP 2 LAST CDS_SEC 1
J 0
(-2425 -1025);
DISPLAY 1.021277 (-2425 -1025);
DISPLAY INVISIBLE (-2425 -1025);
FORCEPROP 1 LAST PATH I1
J 0
(-2425 -1075);
DISPLAY 0.978723 (-2425 -1075);
PAINT WHITE (-2425 -1075);
DISPLAY INVISIBLE (-2425 -1075);
FORCEADD UNIVERSAL_POWER..1
(-2725 2025);
FORCEPROP 3 LASTPIN (-2725 1975) SIG_NAME PVNN_MAIN_CPU0\g
J 0
(-2715 1985);
DISPLAY 0.659574 (-2715 1985);
PAINT MONO (-2715 1985);
DISPLAY INVISIBLE (-2715 1985);
FORCEPROP 1 LAST HDL_POWER PVNN_MAIN_CPU0
J 1
(-2725 2075);
DISPLAY 0.872340 (-2725 2075);
PAINT GREEN (-2725 2075);
FORCEPROP 2 LAST CDS_LIB logical_power
J 0
(-2725 2025);
DISPLAY INVISIBLE (-2725 2025);
FORCEPROP 1 LAST PATH I10
J 0
(-2675 2050);
DISPLAY 0.872340 (-2675 2050);
PAINT AQUA (-2675 2050);
DISPLAY INVISIBLE (-2675 2050);
FORCEADD UNIVERSAL_POWER..1
(-2275 1925);
FORCEPROP 3 LASTPIN (-2275 1875) SIG_NAME PVCCINFAON_CPU0\g
J 0
(-2265 1885);
DISPLAY 0.659574 (-2265 1885);
PAINT MONO (-2265 1885);
DISPLAY INVISIBLE (-2265 1885);
FORCEPROP 1 LAST HDL_POWER PVCCINFAON_CPU0
J 1
(-2275 1975);
DISPLAY 0.872340 (-2275 1975);
PAINT GREEN (-2275 1975);
FORCEPROP 2 LAST CDS_LIB logical_power
J 0
(-2275 1925);
PAINT MONO (-2275 1925);
DISPLAY INVISIBLE (-2275 1925);
FORCEPROP 1 LAST PATH I11
J 0
(-2225 1950);
DISPLAY 0.872340 (-2225 1950);
PAINT AQUA (-2225 1950);
DISPLAY INVISIBLE (-2225 1950);
FORCEADD Q_RES..1
(-1800 1500);
FORCEPROP 1 LAST PART_NUMBER CS00007T200
J 0
(-1900 1425);
DISPLAY 0.638298 (-1900 1425);
DISPLAY INVISIBLE (-1900 1425);
FORCEPROP 1 LAST TOLERANCE 
J 0
(-1500 1500);
DISPLAY 0.638298 (-1500 1500);
FORCEPROP 1 LAST PACK_TYPE 1206LF
J 0
(-1900 1375);
DISPLAY 0.638298 (-1900 1375);
FORCEPROP 1 LAST MATERIAL CHIP
J 0
(-1475 1500);
DISPLAY 0.638298 (-1475 1500);
FORCEPROP 1 LAST VALUE 0
J 2
(-1525 1500);
DISPLAY 0.638298 (-1525 1500);
FORCEPROP 1 LAST WATTAGE 1/2W
J 2
(-1575 1375);
DISPLAY 0.638298 (-1575 1375);
FORCEPROP 1 LAST $LOCATION R324
J 0
(-2025 1500);
DISPLAY 0.787234 (-2025 1500);
FORCEPROP 1 LASTPIN (-1900 1500) $PN 1
J 0
(-1888 1512);
DISPLAY 0.787234 (-1888 1512);
FORCEPROP 1 LASTPIN (-1700 1500) $PN 2
J 0
(-1738 1512);
DISPLAY 0.787234 (-1738 1512);
FORCEPROP 2 LAST CDS_LIB pure_quanta
J 0
(-1800 1500);
PAINT MONO (-1800 1500);
DISPLAY INVISIBLE (-1800 1500);
FORCEPROP 2 LAST CDS_LOCATION R324
J 0
(-1850 1700);
DISPLAY 1.021277 (-1850 1700);
DISPLAY INVISIBLE (-1850 1700);
FORCEPROP 2 LAST $SEC 1
J 0
(-1850 1700);
DISPLAY 0.680851 (-1850 1700);
PAINT MONO (-1850 1700);
DISPLAY INVISIBLE (-1850 1700);
FORCEPROP 2 LAST CDS_SEC 1
J 0
(-1850 1700);
DISPLAY 1.021277 (-1850 1700);
DISPLAY INVISIBLE (-1850 1700);
FORCEPROP 1 LAST PATH I12
J 0
(-1850 1650);
DISPLAY 0.978723 (-1850 1650);
PAINT WHITE (-1850 1650);
DISPLAY INVISIBLE (-1850 1650);
FORCEADD Q_RES..1
(-1800 1750);
FORCEPROP 1 LAST PART_NUMBER CS00007T200
J 0
(-1900 1675);
DISPLAY 0.638298 (-1900 1675);
DISPLAY INVISIBLE (-1900 1675);
FORCEPROP 1 LAST PACK_TYPE 1206LF
J 0
(-1900 1625);
DISPLAY 0.638298 (-1900 1625);
FORCEPROP 1 LAST VALUE 0
J 2
(-1525 1750);
DISPLAY 0.638298 (-1525 1750);
FORCEPROP 1 LAST TOLERANCE 
J 0
(-1500 1750);
DISPLAY 0.638298 (-1500 1750);
FORCEPROP 1 LAST WATTAGE 1/2W
J 2
(-1575 1625);
DISPLAY 0.638298 (-1575 1625);
FORCEPROP 1 LAST MATERIAL EMPTY
J 0
(-1475 1750);
DISPLAY 0.638298 (-1475 1750);
PAINT RED (-1475 1750);
FORCEPROP 1 LAST $LOCATION R323
J 0
(-2025 1750);
DISPLAY 0.787234 (-2025 1750);
FORCEPROP 1 LASTPIN (-1900 1750) $PN 1
J 0
(-1888 1762);
DISPLAY 0.787234 (-1888 1762);
FORCEPROP 1 LASTPIN (-1700 1750) $PN 2
J 0
(-1738 1762);
DISPLAY 0.787234 (-1738 1762);
FORCEPROP 2 LAST CDS_LIB pure_quanta
J 0
(-1800 1750);
PAINT MONO (-1800 1750);
DISPLAY INVISIBLE (-1800 1750);
FORCEPROP 2 LAST CDS_LOCATION R323
J 0
(-1850 1950);
DISPLAY 1.021277 (-1850 1950);
DISPLAY INVISIBLE (-1850 1950);
FORCEPROP 2 LAST $SEC 1
J 0
(-1850 1950);
DISPLAY 0.680851 (-1850 1950);
PAINT MONO (-1850 1950);
DISPLAY INVISIBLE (-1850 1950);
FORCEPROP 2 LAST CDS_SEC 1
J 0
(-1850 1950);
DISPLAY 1.021277 (-1850 1950);
DISPLAY INVISIBLE (-1850 1950);
FORCEPROP 1 LAST PATH I13
J 0
(-1850 1900);
DISPLAY 0.978723 (-1850 1900);
PAINT WHITE (-1850 1900);
DISPLAY INVISIBLE (-1850 1900);
FORCEADD OFFPAGE..2
(-550 -1225);
FORCEPROP 2 LAST $XR1 213 
J 0
(-271 -1225);
DISPLAY 0.638298 (-271 -1225);
PAINT MONO (-271 -1225);
FORCEPROP 2 LAST $XR0 15 
J 0
(-361 -1225);
DISPLAY 0.638298 (-361 -1225);
PAINT MONO (-361 -1225);
FORCEPROP 2 LAST CDS_LIB standard
J 0
(-550 -1225);
DISPLAY INVISIBLE (-550 -1225);
FORCEPROP 1 LAST OFFPAGE TRUE
J 0
(-225 -1350);
DISPLAY 0.872340 (-225 -1350);
PAINT GREEN (-225 -1350);
DISPLAY INVISIBLE (-225 -1350);
FORCEPROP 1 LAST COMMENT_BODY TRUE
J 0
(-595 -1320);
DISPLAY 0.872340 (-595 -1320);
PAINT GREEN (-595 -1320);
DISPLAY INVISIBLE (-595 -1320);
FORCEPROP 2 LAST PATH I14
J 0
(-250 -1175);
DISPLAY 1.021277 (-250 -1175);
DISPLAY INVISIBLE (-250 -1175);
FORCEADD OFFPAGE..2
(-550 -1100);
FORCEPROP 2 LAST $XR0 15 
J 0
(-361 -1100);
DISPLAY 0.638298 (-361 -1100);
PAINT MONO (-361 -1100);
FORCEPROP 2 LAST CDS_LIB standard
J 0
(-550 -1100);
DISPLAY INVISIBLE (-550 -1100);
FORCEPROP 1 LAST OFFPAGE TRUE
J 0
(-225 -1225);
DISPLAY 0.872340 (-225 -1225);
PAINT GREEN (-225 -1225);
DISPLAY INVISIBLE (-225 -1225);
FORCEPROP 1 LAST COMMENT_BODY TRUE
J 0
(-595 -1195);
DISPLAY 0.872340 (-595 -1195);
PAINT GREEN (-595 -1195);
DISPLAY INVISIBLE (-595 -1195);
FORCEPROP 2 LAST PATH I15
J 0
(-225 -1050);
DISPLAY 1.021277 (-225 -1050);
DISPLAY INVISIBLE (-225 -1050);
FORCEADD OFFPAGE..2
(-550 -975);
FORCEPROP 2 LAST $XR0 15 
J 0
(-361 -975);
DISPLAY 0.638298 (-361 -975);
PAINT MONO (-361 -975);
FORCEPROP 2 LAST CDS_LIB standard
J 0
(-550 -975);
DISPLAY INVISIBLE (-550 -975);
FORCEPROP 1 LAST OFFPAGE TRUE
J 0
(-225 -1100);
DISPLAY 0.872340 (-225 -1100);
PAINT GREEN (-225 -1100);
DISPLAY INVISIBLE (-225 -1100);
FORCEPROP 1 LAST COMMENT_BODY TRUE
J 0
(-595 -1070);
DISPLAY 0.872340 (-595 -1070);
PAINT GREEN (-595 -1070);
DISPLAY INVISIBLE (-595 -1070);
FORCEPROP 2 LAST PATH I16
J 0
(-350 -925);
DISPLAY 1.021277 (-350 -925);
DISPLAY INVISIBLE (-350 -925);
FORCEADD OFFPAGE..2
(-550 -850);
FORCEPROP 2 LAST $XR0 15 
J 0
(-361 -850);
DISPLAY 0.638298 (-361 -850);
PAINT MONO (-361 -850);
FORCEPROP 2 LAST CDS_LIB standard
J 0
(-550 -850);
DISPLAY INVISIBLE (-550 -850);
FORCEPROP 1 LAST OFFPAGE TRUE
J 0
(-225 -975);
DISPLAY 0.872340 (-225 -975);
PAINT GREEN (-225 -975);
DISPLAY INVISIBLE (-225 -975);
FORCEPROP 1 LAST COMMENT_BODY TRUE
J 0
(-595 -945);
DISPLAY 0.872340 (-595 -945);
PAINT GREEN (-595 -945);
DISPLAY INVISIBLE (-595 -945);
FORCEPROP 2 LAST PATH I17
J 0
(-350 -800);
DISPLAY 1.021277 (-350 -800);
DISPLAY INVISIBLE (-350 -800);
FORCEADD UNIVERSAL_POWER..1
(425 -600);
FORCEPROP 3 LASTPIN (425 -650) SIG_NAME P3V3_AUX\g
J 0
(435 -640);
DISPLAY 0.659574 (435 -640);
PAINT MONO (435 -640);
DISPLAY INVISIBLE (435 -640);
FORCEPROP 1 LAST HDL_POWER P3V3_AUX
J 1
(425 -550);
DISPLAY 0.872340 (425 -550);
PAINT GREEN (425 -550);
FORCEPROP 2 LAST CDS_LIB logical_power
J 0
(425 -600);
DISPLAY INVISIBLE (425 -600);
FORCEPROP 1 LAST PATH I18
J 0
(475 -575);
DISPLAY 0.872340 (475 -575);
PAINT AQUA (475 -575);
DISPLAY INVISIBLE (475 -575);
FORCEADD UNIVERSAL_GND..1
(400 375);
FORCEPROP 3 LASTPIN (400 425) SIG_NAME GND\g
J 0
(410 435);
DISPLAY 0.659574 (410 435);
PAINT MONO (410 435);
DISPLAY INVISIBLE (410 435);
FORCEPROP 2 LAST CDS_LIB logical_power
J 0
(400 375);
DISPLAY INVISIBLE (400 375);
FORCEPROP 1 LAST HDL_POWER GND
J 1
(425 300);
DISPLAY 0.872340 (425 300);
PAINT GREEN (425 300);
DISPLAY INVISIBLE (425 300);
FORCEPROP 1 LAST PATH I19
J 0
(475 375);
DISPLAY 0.872340 (475 375);
PAINT AQUA (475 375);
DISPLAY INVISIBLE (475 375);
FORCEADD Q_RES..1
(-2375 -1100);
FORCEPROP 1 LAST PART_NUMBER CS31002FB08
J 0
(-2500 -1025);
DISPLAY 0.638298 (-2500 -1025);
DISPLAY INVISIBLE (-2500 -1025);
FORCEPROP 1 LAST TOLERANCE 1%
J 0
(-2125 -1100);
DISPLAY 0.638298 (-2125 -1100);
FORCEPROP 1 LAST VALUE 10K
J 2
(-2150 -1100);
DISPLAY 0.638298 (-2150 -1100);
FORCEPROP 1 LAST MATERIAL CHIP
J 0
(-2000 -1100);
DISPLAY 0.638298 (-2000 -1100);
FORCEPROP 1 LAST $LOCATION R321
J 0
(-2625 -1100);
DISPLAY 0.787234 (-2625 -1100);
FORCEPROP 1 LASTPIN (-2475 -1100) $PN 1
J 0
(-2463 -1088);
DISPLAY 0.787234 (-2463 -1088);
FORCEPROP 1 LASTPIN (-2275 -1100) $PN 2
J 0
(-2313 -1088);
DISPLAY 0.787234 (-2313 -1088);
FORCEPROP 1 LAST WATTAGE 1/16W
J 2
(-2150 -975);
DISPLAY 0.638298 (-2150 -975);
DISPLAY INVISIBLE (-2150 -975);
FORCEPROP 2 LAST CDS_LIB pure_quanta
J 0
(-2375 -1100);
PAINT MONO (-2375 -1100);
DISPLAY INVISIBLE (-2375 -1100);
FORCEPROP 1 LAST PACK_TYPE 0402LF
J 0
(-2275 -1050);
DISPLAY 0.638298 (-2275 -1050);
DISPLAY INVISIBLE (-2275 -1050);
FORCEPROP 2 LAST CDS_LOCATION R321
J 0
(-2425 -900);
DISPLAY 1.021277 (-2425 -900);
DISPLAY INVISIBLE (-2425 -900);
FORCEPROP 2 LAST $SEC 1
J 0
(-2425 -900);
DISPLAY 0.680851 (-2425 -900);
PAINT MONO (-2425 -900);
DISPLAY INVISIBLE (-2425 -900);
FORCEPROP 2 LAST CDS_SEC 1
J 0
(-2425 -900);
DISPLAY 1.021277 (-2425 -900);
DISPLAY INVISIBLE (-2425 -900);
FORCEPROP 1 LAST PATH I2
J 0
(-2425 -950);
DISPLAY 0.978723 (-2425 -950);
PAINT WHITE (-2425 -950);
DISPLAY INVISIBLE (-2425 -950);
FORCEADD Q_CAP..1
(400 700);
FORCEPROP 1 LAST PART_NUMBER CH622KMEB01
J 0
(450 550);
DISPLAY 0.638298 (450 550);
DISPLAY INVISIBLE (450 550);
FORCEPROP 1 LAST VOLTAGE 4V
J 0
(450 700);
DISPLAY 0.638298 (450 700);
FORCEPROP 1 LAST PACK_TYPE C0402
J 0
(450 500);
DISPLAY 0.638298 (450 500);
FORCEPROP 1 LAST VALUE 22UF
J 0
(450 750);
DISPLAY 0.638298 (450 750);
FORCEPROP 1 LAST MATERIAL X6S
J 0
(450 600);
DISPLAY 0.638298 (450 600);
FORCEPROP 1 LAST TOLERANCE 20%
J 0
(450 650);
DISPLAY 0.638298 (450 650);
FORCEPROP 1 LAST $LOCATION C1365
J 0
(450 800);
DISPLAY 0.787234 (450 800);
FORCEPROP 1 LASTPIN (400 800) $PN 1
J 0
(410 780);
DISPLAY 0.787234 (410 780);
PAINT MONO (410 780);
FORCEPROP 1 LASTPIN (400 600) $PN 2
J 0
(410 580);
DISPLAY 0.787234 (410 580);
PAINT MONO (410 580);
FORCEPROP 2 LAST CDS_LIB pure_quanta
J 0
(400 700);
DISPLAY INVISIBLE (400 700);
FORCEPROP 0 LAST CDS_LOCATION C1365
J 0
(450 850);
DISPLAY 1.021277 (450 850);
DISPLAY INVISIBLE (450 850);
FORCEPROP 0 LAST $SEC 1
J 0
(450 850);
DISPLAY 0.680851 (450 850);
PAINT MONO (450 850);
DISPLAY INVISIBLE (450 850);
FORCEPROP 0 LAST CDS_SEC 1
J 0
(450 850);
DISPLAY 1.021277 (450 850);
DISPLAY INVISIBLE (450 850);
FORCEPROP 1 LAST PATH I20
J 0
(450 850);
DISPLAY 0.978723 (450 850);
PAINT WHITE (450 850);
DISPLAY INVISIBLE (450 850);
FORCEADD UNIVERSAL_POWER..1
(400 975);
FORCEPROP 3 LASTPIN (400 925) SIG_NAME PVNN_MAIN_CPU1\g
J 0
(410 935);
DISPLAY 0.659574 (410 935);
PAINT MONO (410 935);
DISPLAY INVISIBLE (410 935);
FORCEPROP 1 LAST HDL_POWER PVNN_MAIN_CPU1
J 1
(450 1025);
DISPLAY 1.085106 (450 1025);
PAINT GREEN (450 1025);
FORCEPROP 2 LAST CDS_LIB logical_power
J 0
(400 975);
DISPLAY INVISIBLE (400 975);
FORCEPROP 1 LAST PATH I21
J 0
(450 1000);
DISPLAY 0.872340 (450 1000);
PAINT AQUA (450 1000);
DISPLAY INVISIBLE (450 1000);
FORCEADD Q_RES..1
(775 -1225);
FORCEPROP 1 LAST PART_NUMBER CS21502FB07
J 0
(650 -1300);
DISPLAY 0.638298 (650 -1300);
DISPLAY INVISIBLE (650 -1300);
FORCEPROP 1 LAST PACK_TYPE 0402LF
J 0
(650 -1350);
DISPLAY 0.638298 (650 -1350);
FORCEPROP 1 LAST MATERIAL CHIP
J 0
(1150 -1225);
DISPLAY 0.638298 (1150 -1225);
FORCEPROP 1 LAST WATTAGE 1/16W
J 2
(1025 -1350);
DISPLAY 0.638298 (1025 -1350);
FORCEPROP 1 LAST TOLERANCE 1%
J 0
(1025 -1225);
DISPLAY 0.638298 (1025 -1225);
FORCEPROP 1 LAST VALUE 1.5K
J 2
(1000 -1225);
DISPLAY 0.638298 (1000 -1225);
FORCEPROP 1 LAST $LOCATION R1217
J 0
(525 -1225);
DISPLAY 0.787234 (525 -1225);
FORCEPROP 1 LASTPIN (675 -1225) $PN 1
J 0
(687 -1213);
DISPLAY 0.787234 (687 -1213);
PAINT MONO (687 -1213);
FORCEPROP 1 LASTPIN (875 -1225) $PN 2
J 0
(837 -1213);
DISPLAY 0.787234 (837 -1213);
PAINT MONO (837 -1213);
FORCEPROP 2 LAST CDS_LIB pure_quanta
J 0
(775 -1225);
DISPLAY INVISIBLE (775 -1225);
FORCEPROP 2 LAST CDS_LOCATION R1217
J 0
(725 -1025);
DISPLAY 1.021277 (725 -1025);
DISPLAY INVISIBLE (725 -1025);
FORCEPROP 0 LAST $SEC 1
J 0
(1150 -1175);
DISPLAY 0.680851 (1150 -1175);
PAINT MONO (1150 -1175);
DISPLAY INVISIBLE (1150 -1175);
FORCEPROP 2 LAST CDS_SEC 1
J 0
(725 -1025);
DISPLAY 1.021277 (725 -1025);
DISPLAY INVISIBLE (725 -1025);
FORCEPROP 1 LAST PATH I22
J 0
(725 -1075);
DISPLAY 0.978723 (725 -1075);
PAINT WHITE (725 -1075);
DISPLAY INVISIBLE (725 -1075);
FORCEADD OFFPAGE..2
(2600 -1225);
FORCEPROP 2 LAST $XR1 213 
J 0
(2879 -1225);
DISPLAY 0.638298 (2879 -1225);
PAINT MONO (2879 -1225);
FORCEPROP 2 LAST $XR0 46 
J 0
(2789 -1225);
DISPLAY 0.638298 (2789 -1225);
PAINT MONO (2789 -1225);
FORCEPROP 2 LAST CDS_LIB standard
J 0
(2600 -1225);
DISPLAY INVISIBLE (2600 -1225);
FORCEPROP 1 LAST OFFPAGE TRUE
J 0
(2925 -1350);
DISPLAY 0.872340 (2925 -1350);
PAINT GREEN (2925 -1350);
DISPLAY INVISIBLE (2925 -1350);
FORCEPROP 1 LAST COMMENT_BODY TRUE
J 0
(2555 -1320);
DISPLAY 0.872340 (2555 -1320);
PAINT GREEN (2555 -1320);
DISPLAY INVISIBLE (2555 -1320);
FORCEPROP 2 LAST PATH I23
J 0
(2900 -1175);
DISPLAY 1.021277 (2900 -1175);
DISPLAY INVISIBLE (2900 -1175);
FORCEADD OFFPAGE..2
(2600 -1100);
FORCEPROP 2 LAST $XR0 46 
J 0
(2789 -1100);
DISPLAY 0.638298 (2789 -1100);
PAINT MONO (2789 -1100);
FORCEPROP 2 LAST CDS_LIB standard
J 0
(2600 -1100);
DISPLAY INVISIBLE (2600 -1100);
FORCEPROP 1 LAST OFFPAGE TRUE
J 0
(2925 -1225);
DISPLAY 0.872340 (2925 -1225);
PAINT GREEN (2925 -1225);
DISPLAY INVISIBLE (2925 -1225);
FORCEPROP 1 LAST COMMENT_BODY TRUE
J 0
(2555 -1195);
DISPLAY 0.872340 (2555 -1195);
PAINT GREEN (2555 -1195);
DISPLAY INVISIBLE (2555 -1195);
FORCEPROP 2 LAST PATH I24
J 0
(2925 -1050);
DISPLAY 1.021277 (2925 -1050);
DISPLAY INVISIBLE (2925 -1050);
FORCEADD Q_RES..1
(775 -1100);
FORCEPROP 1 LAST PART_NUMBER CS31002FB08
J 0
(650 -1025);
DISPLAY 0.638298 (650 -1025);
DISPLAY INVISIBLE (650 -1025);
FORCEPROP 1 LAST VALUE 10K
J 2
(1000 -1100);
DISPLAY 0.638298 (1000 -1100);
FORCEPROP 1 LAST TOLERANCE 1%
J 0
(1025 -1100);
DISPLAY 0.638298 (1025 -1100);
FORCEPROP 1 LAST MATERIAL CHIP
J 0
(1150 -1100);
DISPLAY 0.638298 (1150 -1100);
FORCEPROP 1 LAST $LOCATION R327
J 0
(525 -1100);
DISPLAY 0.787234 (525 -1100);
FORCEPROP 1 LASTPIN (675 -1100) $PN 1
J 0
(687 -1088);
DISPLAY 0.787234 (687 -1088);
FORCEPROP 1 LASTPIN (875 -1100) $PN 2
J 0
(837 -1088);
DISPLAY 0.787234 (837 -1088);
FORCEPROP 2 LAST CDS_LIB pure_quanta
J 0
(775 -1100);
PAINT MONO (775 -1100);
DISPLAY INVISIBLE (775 -1100);
FORCEPROP 1 LAST WATTAGE 1/16W
J 2
(1000 -975);
DISPLAY 0.638298 (1000 -975);
DISPLAY INVISIBLE (1000 -975);
FORCEPROP 1 LAST PACK_TYPE 0402LF
J 0
(1125 -1100);
DISPLAY 0.638298 (1125 -1100);
DISPLAY INVISIBLE (1125 -1100);
FORCEPROP 2 LAST CDS_LOCATION R327
J 0
(725 -900);
DISPLAY 1.021277 (725 -900);
DISPLAY INVISIBLE (725 -900);
FORCEPROP 2 LAST $SEC 1
J 0
(725 -900);
DISPLAY 0.680851 (725 -900);
PAINT MONO (725 -900);
DISPLAY INVISIBLE (725 -900);
FORCEPROP 2 LAST CDS_SEC 1
J 0
(725 -900);
DISPLAY 1.021277 (725 -900);
DISPLAY INVISIBLE (725 -900);
FORCEPROP 1 LAST PATH I25
J 0
(725 -950);
DISPLAY 0.978723 (725 -950);
PAINT WHITE (725 -950);
DISPLAY INVISIBLE (725 -950);
FORCEADD Q_RES..1
(775 -975);
FORCEPROP 1 LAST PART_NUMBER CS31002FB08
J 0
(650 -900);
DISPLAY 0.638298 (650 -900);
DISPLAY INVISIBLE (650 -900);
FORCEPROP 1 LAST TOLERANCE 1%
J 0
(1025 -975);
DISPLAY 0.638298 (1025 -975);
FORCEPROP 1 LAST MATERIAL CHIP
J 0
(1150 -975);
DISPLAY 0.638298 (1150 -975);
FORCEPROP 1 LAST VALUE 10K
J 2
(1000 -975);
DISPLAY 0.638298 (1000 -975);
FORCEPROP 1 LAST $LOCATION R326
J 0
(525 -975);
DISPLAY 0.787234 (525 -975);
FORCEPROP 1 LASTPIN (675 -975) $PN 1
J 0
(687 -963);
DISPLAY 0.787234 (687 -963);
FORCEPROP 1 LASTPIN (875 -975) $PN 2
J 0
(837 -963);
DISPLAY 0.787234 (837 -963);
FORCEPROP 2 LAST CDS_LIB pure_quanta
J 0
(775 -975);
PAINT MONO (775 -975);
DISPLAY INVISIBLE (775 -975);
FORCEPROP 1 LAST WATTAGE 1/16W
J 2
(1000 -850);
DISPLAY 0.638298 (1000 -850);
DISPLAY INVISIBLE (1000 -850);
FORCEPROP 1 LAST PACK_TYPE 0402LF
J 0
(1125 -975);
DISPLAY 0.638298 (1125 -975);
DISPLAY INVISIBLE (1125 -975);
FORCEPROP 2 LAST CDS_LOCATION R326
J 0
(725 -775);
DISPLAY 1.021277 (725 -775);
DISPLAY INVISIBLE (725 -775);
FORCEPROP 2 LAST $SEC 1
J 0
(725 -775);
DISPLAY 0.680851 (725 -775);
PAINT MONO (725 -775);
DISPLAY INVISIBLE (725 -775);
FORCEPROP 2 LAST CDS_SEC 1
J 0
(725 -775);
DISPLAY 1.021277 (725 -775);
DISPLAY INVISIBLE (725 -775);
FORCEPROP 1 LAST PATH I26
J 0
(725 -825);
DISPLAY 0.978723 (725 -825);
PAINT WHITE (725 -825);
DISPLAY INVISIBLE (725 -825);
FORCEADD Q_RES..1
(775 -850);
FORCEPROP 1 LAST PART_NUMBER CS31002FB08
J 0
(650 -775);
DISPLAY 0.638298 (650 -775);
DISPLAY INVISIBLE (650 -775);
FORCEPROP 1 LAST TOLERANCE 1%
J 0
(1025 -850);
DISPLAY 0.638298 (1025 -850);
FORCEPROP 1 LAST VALUE 10K
J 2
(1000 -850);
DISPLAY 0.638298 (1000 -850);
FORCEPROP 1 LAST PACK_TYPE 0402LF
J 0
(650 -725);
DISPLAY 0.638298 (650 -725);
FORCEPROP 1 LAST WATTAGE 1/16W
J 2
(1000 -725);
DISPLAY 0.638298 (1000 -725);
FORCEPROP 1 LAST MATERIAL CHIP
J 0
(1150 -850);
DISPLAY 0.638298 (1150 -850);
FORCEPROP 1 LAST $LOCATION R325
J 0
(525 -850);
DISPLAY 0.787234 (525 -850);
FORCEPROP 1 LASTPIN (675 -850) $PN 1
J 0
(687 -838);
DISPLAY 0.787234 (687 -838);
FORCEPROP 1 LASTPIN (875 -850) $PN 2
J 0
(837 -838);
DISPLAY 0.787234 (837 -838);
FORCEPROP 2 LAST CDS_LIB pure_quanta
J 0
(775 -850);
PAINT MONO (775 -850);
DISPLAY INVISIBLE (775 -850);
FORCEPROP 2 LAST CDS_LOCATION R325
J 0
(725 -650);
DISPLAY 1.021277 (725 -650);
DISPLAY INVISIBLE (725 -650);
FORCEPROP 2 LAST $SEC 1
J 0
(725 -650);
DISPLAY 0.680851 (725 -650);
PAINT MONO (725 -650);
DISPLAY INVISIBLE (725 -650);
FORCEPROP 2 LAST CDS_SEC 1
J 0
(725 -650);
DISPLAY 1.021277 (725 -650);
DISPLAY INVISIBLE (725 -650);
FORCEPROP 1 LAST PATH I27
J 0
(725 -700);
DISPLAY 0.978723 (725 -700);
PAINT WHITE (725 -700);
DISPLAY INVISIBLE (725 -700);
FORCEADD Q_CAP..1
(775 700);
FORCEPROP 1 LAST PART_NUMBER CH622KMEB01
J 0
(825 550);
DISPLAY 0.638298 (825 550);
DISPLAY INVISIBLE (825 550);
FORCEPROP 1 LAST VOLTAGE 4V
J 0
(825 700);
DISPLAY 0.638298 (825 700);
FORCEPROP 1 LAST MATERIAL X6S
J 0
(825 600);
DISPLAY 0.638298 (825 600);
FORCEPROP 1 LAST TOLERANCE 20%
J 0
(825 650);
DISPLAY 0.638298 (825 650);
FORCEPROP 1 LAST PACK_TYPE C0402
J 0
(825 500);
DISPLAY 0.638298 (825 500);
FORCEPROP 1 LAST VALUE 22UF
J 0
(825 750);
DISPLAY 0.638298 (825 750);
FORCEPROP 1 LAST $LOCATION C1366
J 0
(825 800);
DISPLAY 0.787234 (825 800);
FORCEPROP 1 LASTPIN (775 800) $PN 1
J 0
(785 780);
DISPLAY 0.787234 (785 780);
PAINT MONO (785 780);
FORCEPROP 1 LASTPIN (775 600) $PN 2
J 0
(785 580);
DISPLAY 0.787234 (785 580);
PAINT MONO (785 580);
FORCEPROP 2 LAST CDS_LIB pure_quanta
J 0
(775 700);
DISPLAY INVISIBLE (775 700);
FORCEPROP 0 LAST CDS_LOCATION C1366
J 0
(825 850);
DISPLAY 1.021277 (825 850);
DISPLAY INVISIBLE (825 850);
FORCEPROP 0 LAST $SEC 1
J 0
(825 850);
DISPLAY 0.680851 (825 850);
PAINT MONO (825 850);
DISPLAY INVISIBLE (825 850);
FORCEPROP 0 LAST CDS_SEC 1
J 0
(825 850);
DISPLAY 1.021277 (825 850);
DISPLAY INVISIBLE (825 850);
FORCEPROP 1 LAST PATH I28
J 0
(825 850);
DISPLAY 0.978723 (825 850);
PAINT WHITE (825 850);
DISPLAY INVISIBLE (825 850);
FORCEADD OFFPAGE..2
(2600 -975);
FORCEPROP 2 LAST $XR0 46 
J 0
(2789 -975);
DISPLAY 0.638298 (2789 -975);
PAINT MONO (2789 -975);
FORCEPROP 2 LAST CDS_LIB standard
J 0
(2600 -975);
DISPLAY INVISIBLE (2600 -975);
FORCEPROP 1 LAST OFFPAGE TRUE
J 0
(2925 -1100);
DISPLAY 0.872340 (2925 -1100);
PAINT GREEN (2925 -1100);
DISPLAY INVISIBLE (2925 -1100);
FORCEPROP 1 LAST COMMENT_BODY TRUE
J 0
(2555 -1070);
DISPLAY 0.872340 (2555 -1070);
PAINT GREEN (2555 -1070);
DISPLAY INVISIBLE (2555 -1070);
FORCEPROP 2 LAST PATH I29
J 0
(2800 -925);
DISPLAY 1.021277 (2800 -925);
DISPLAY INVISIBLE (2800 -925);
FORCEADD UNIVERSAL_POWER..1
(-2725 -600);
FORCEPROP 3 LASTPIN (-2725 -650) SIG_NAME P3V3_AUX\g
J 0
(-2715 -640);
DISPLAY 0.659574 (-2715 -640);
PAINT MONO (-2715 -640);
DISPLAY INVISIBLE (-2715 -640);
FORCEPROP 1 LAST HDL_POWER P3V3_AUX
J 1
(-2725 -550);
DISPLAY 0.872340 (-2725 -550);
PAINT GREEN (-2725 -550);
FORCEPROP 2 LAST CDS_LIB logical_power
J 0
(-2725 -600);
DISPLAY INVISIBLE (-2725 -600);
FORCEPROP 1 LAST PATH I3
J 0
(-2675 -575);
DISPLAY 0.872340 (-2675 -575);
PAINT AQUA (-2675 -575);
DISPLAY INVISIBLE (-2675 -575);
FORCEADD OFFPAGE..2
(2600 -850);
FORCEPROP 2 LAST $XR0 46 
J 0
(2789 -850);
DISPLAY 0.638298 (2789 -850);
PAINT MONO (2789 -850);
FORCEPROP 2 LAST CDS_LIB standard
J 0
(2600 -850);
DISPLAY INVISIBLE (2600 -850);
FORCEPROP 1 LAST OFFPAGE TRUE
J 0
(2925 -975);
DISPLAY 0.872340 (2925 -975);
PAINT GREEN (2925 -975);
DISPLAY INVISIBLE (2925 -975);
FORCEPROP 1 LAST COMMENT_BODY TRUE
J 0
(2555 -945);
DISPLAY 0.872340 (2555 -945);
PAINT GREEN (2555 -945);
DISPLAY INVISIBLE (2555 -945);
FORCEPROP 2 LAST PATH I30
J 0
(2800 -800);
DISPLAY 1.021277 (2800 -800);
DISPLAY INVISIBLE (2800 -800);
FORCEADD UNIVERSAL_POWER..1
(-1175 2025);
FORCEPROP 3 LASTPIN (-1175 1975) SIG_NAME PVNN_TERM_CPU0\g
J 0
(-1165 1985);
DISPLAY 0.659574 (-1165 1985);
PAINT MONO (-1165 1985);
DISPLAY INVISIBLE (-1165 1985);
FORCEPROP 1 LAST HDL_POWER PVNN_TERM_CPU0
J 1
(-1175 2075);
DISPLAY 0.872340 (-1175 2075);
PAINT GREEN (-1175 2075);
FORCEPROP 2 LAST CDS_LIB logical_power
J 0
(-1175 2025);
PAINT MONO (-1175 2025);
DISPLAY INVISIBLE (-1175 2025);
FORCEPROP 1 LAST PATH I31
J 0
(-1125 2050);
DISPLAY 0.872340 (-1125 2050);
PAINT AQUA (-1125 2050);
DISPLAY INVISIBLE (-1125 2050);
FORCEADD UNIVERSAL_POWER..1
(425 2025);
FORCEPROP 3 LASTPIN (425 1975) SIG_NAME PVNN_MAIN_CPU1\g
J 0
(435 1985);
DISPLAY 0.659574 (435 1985);
PAINT MONO (435 1985);
DISPLAY INVISIBLE (435 1985);
FORCEPROP 1 LAST HDL_POWER PVNN_MAIN_CPU1
J 1
(425 2075);
DISPLAY 0.872340 (425 2075);
PAINT GREEN (425 2075);
FORCEPROP 2 LAST CDS_LIB logical_power
J 0
(425 2025);
DISPLAY INVISIBLE (425 2025);
FORCEPROP 1 LAST PATH I32
J 0
(475 2050);
DISPLAY 0.872340 (475 2050);
PAINT AQUA (475 2050);
DISPLAY INVISIBLE (475 2050);
FORCEADD UNIVERSAL_POWER..1
(875 1925);
FORCEPROP 3 LASTPIN (875 1875) SIG_NAME PVCCINFAON_CPU1\g
J 0
(885 1885);
DISPLAY 0.659574 (885 1885);
PAINT MONO (885 1885);
DISPLAY INVISIBLE (885 1885);
FORCEPROP 1 LAST HDL_POWER PVCCINFAON_CPU1
J 1
(875 1975);
DISPLAY 0.872340 (875 1975);
PAINT GREEN (875 1975);
FORCEPROP 2 LAST CDS_LIB logical_power
J 0
(875 1925);
PAINT MONO (875 1925);
DISPLAY INVISIBLE (875 1925);
FORCEPROP 1 LAST PATH I33
J 0
(925 1950);
DISPLAY 0.872340 (925 1950);
PAINT AQUA (925 1950);
DISPLAY INVISIBLE (925 1950);
FORCEADD Q_RES..1
(1350 1500);
FORCEPROP 1 LAST PART_NUMBER CS00007T200
J 0
(1250 1425);
DISPLAY 0.638298 (1250 1425);
DISPLAY INVISIBLE (1250 1425);
FORCEPROP 1 LAST TOLERANCE 
J 0
(1650 1500);
DISPLAY 0.638298 (1650 1500);
FORCEPROP 1 LAST VALUE 0
J 2
(1625 1500);
DISPLAY 0.638298 (1625 1500);
FORCEPROP 1 LAST MATERIAL CHIP
J 0
(1675 1500);
DISPLAY 0.638298 (1675 1500);
FORCEPROP 1 LAST WATTAGE 1/2W
J 2
(1575 1375);
DISPLAY 0.638298 (1575 1375);
FORCEPROP 1 LAST PACK_TYPE 1206LF
J 0
(1250 1375);
DISPLAY 0.638298 (1250 1375);
FORCEPROP 1 LAST $LOCATION R330
J 0
(1125 1500);
DISPLAY 0.787234 (1125 1500);
FORCEPROP 1 LASTPIN (1250 1500) $PN 1
J 0
(1262 1512);
DISPLAY 0.787234 (1262 1512);
FORCEPROP 1 LASTPIN (1450 1500) $PN 2
J 0
(1412 1512);
DISPLAY 0.787234 (1412 1512);
FORCEPROP 2 LAST CDS_LIB pure_quanta
J 0
(1350 1500);
PAINT MONO (1350 1500);
DISPLAY INVISIBLE (1350 1500);
FORCEPROP 2 LAST CDS_LOCATION R330
J 0
(1300 1700);
DISPLAY 1.021277 (1300 1700);
DISPLAY INVISIBLE (1300 1700);
FORCEPROP 2 LAST $SEC 1
J 0
(1300 1700);
DISPLAY 0.680851 (1300 1700);
PAINT MONO (1300 1700);
DISPLAY INVISIBLE (1300 1700);
FORCEPROP 2 LAST CDS_SEC 1
J 0
(1300 1700);
DISPLAY 1.021277 (1300 1700);
DISPLAY INVISIBLE (1300 1700);
FORCEPROP 1 LAST PATH I34
J 0
(1300 1650);
DISPLAY 0.978723 (1300 1650);
PAINT WHITE (1300 1650);
DISPLAY INVISIBLE (1300 1650);
FORCEADD Q_RES..1
(1350 1750);
FORCEPROP 1 LAST PART_NUMBER CS00007T200
J 0
(1250 1675);
DISPLAY 0.638298 (1250 1675);
DISPLAY INVISIBLE (1250 1675);
FORCEPROP 1 LAST PACK_TYPE 1206LF
J 0
(1250 1625);
DISPLAY 0.638298 (1250 1625);
FORCEPROP 1 LAST VALUE 0
J 2
(1625 1750);
DISPLAY 0.638298 (1625 1750);
FORCEPROP 1 LAST TOLERANCE 
J 0
(1650 1750);
DISPLAY 0.638298 (1650 1750);
FORCEPROP 1 LAST WATTAGE 1/2W
J 2
(1575 1625);
DISPLAY 0.638298 (1575 1625);
FORCEPROP 1 LAST MATERIAL EMPTY
J 0
(1675 1750);
DISPLAY 0.638298 (1675 1750);
PAINT RED (1675 1750);
FORCEPROP 1 LAST $LOCATION R329
J 0
(1125 1750);
DISPLAY 0.787234 (1125 1750);
FORCEPROP 1 LASTPIN (1250 1750) $PN 1
J 0
(1262 1762);
DISPLAY 0.787234 (1262 1762);
FORCEPROP 1 LASTPIN (1450 1750) $PN 2
J 0
(1412 1762);
DISPLAY 0.787234 (1412 1762);
FORCEPROP 2 LAST CDS_LIB pure_quanta
J 0
(1350 1750);
PAINT MONO (1350 1750);
DISPLAY INVISIBLE (1350 1750);
FORCEPROP 2 LAST CDS_LOCATION R329
J 0
(1300 1950);
DISPLAY 1.021277 (1300 1950);
DISPLAY INVISIBLE (1300 1950);
FORCEPROP 2 LAST $SEC 1
J 0
(1300 1950);
DISPLAY 0.680851 (1300 1950);
PAINT MONO (1300 1950);
DISPLAY INVISIBLE (1300 1950);
FORCEPROP 2 LAST CDS_SEC 1
J 0
(1300 1950);
DISPLAY 1.021277 (1300 1950);
DISPLAY INVISIBLE (1300 1950);
FORCEPROP 1 LAST PATH I35
J 0
(1300 1900);
DISPLAY 0.978723 (1300 1900);
PAINT WHITE (1300 1900);
DISPLAY INVISIBLE (1300 1900);
FORCEADD UNIVERSAL_POWER..1
(1975 2025);
FORCEPROP 3 LASTPIN (1975 1975) SIG_NAME PVNN_TERM_CPU1\g
J 0
(1985 1985);
DISPLAY 0.659574 (1985 1985);
PAINT MONO (1985 1985);
DISPLAY INVISIBLE (1985 1985);
FORCEPROP 1 LAST HDL_POWER PVNN_TERM_CPU1
J 1
(1975 2075);
DISPLAY 0.872340 (1975 2075);
PAINT GREEN (1975 2075);
FORCEPROP 2 LAST CDS_LIB logical_power
J 0
(1975 2025);
PAINT MONO (1975 2025);
DISPLAY INVISIBLE (1975 2025);
FORCEPROP 1 LAST PATH I36
J 0
(2025 2050);
DISPLAY 0.872340 (2025 2050);
PAINT AQUA (2025 2050);
DISPLAY INVISIBLE (2025 2050);
FORCEADD UNIVERSAL_GND..1
(-2750 375);
FORCEPROP 3 LASTPIN (-2750 425) SIG_NAME GND\g
J 0
(-2740 435);
DISPLAY 0.659574 (-2740 435);
PAINT MONO (-2740 435);
DISPLAY INVISIBLE (-2740 435);
FORCEPROP 2 LAST CDS_LIB logical_power
J 0
(-2750 375);
DISPLAY INVISIBLE (-2750 375);
FORCEPROP 1 LAST HDL_POWER GND
J 1
(-2725 300);
DISPLAY 0.872340 (-2725 300);
PAINT GREEN (-2725 300);
DISPLAY INVISIBLE (-2725 300);
FORCEPROP 1 LAST PATH I4
J 0
(-2675 375);
DISPLAY 0.872340 (-2675 375);
PAINT AQUA (-2675 375);
DISPLAY INVISIBLE (-2675 375);
FORCEADD Q_CAP..1
(-2750 700);
FORCEPROP 1 LAST PART_NUMBER CH622KMEB01
J 0
(-2700 550);
DISPLAY 0.638298 (-2700 550);
DISPLAY INVISIBLE (-2700 550);
FORCEPROP 1 LAST VOLTAGE 4V
J 0
(-2700 700);
DISPLAY 0.638298 (-2700 700);
FORCEPROP 1 LAST TOLERANCE 20%
J 0
(-2700 650);
DISPLAY 0.638298 (-2700 650);
FORCEPROP 1 LAST MATERIAL X6S
J 0
(-2700 600);
DISPLAY 0.638298 (-2700 600);
FORCEPROP 1 LAST VALUE 22UF
J 0
(-2700 750);
DISPLAY 0.638298 (-2700 750);
FORCEPROP 1 LAST PACK_TYPE C0402
J 0
(-2700 500);
DISPLAY 0.638298 (-2700 500);
FORCEPROP 1 LAST $LOCATION C1363
J 0
(-2700 800);
DISPLAY 0.787234 (-2700 800);
FORCEPROP 1 LASTPIN (-2750 800) $PN 1
J 0
(-2740 780);
DISPLAY 0.787234 (-2740 780);
PAINT MONO (-2740 780);
FORCEPROP 1 LASTPIN (-2750 600) $PN 2
J 0
(-2740 580);
DISPLAY 0.787234 (-2740 580);
PAINT MONO (-2740 580);
FORCEPROP 2 LAST CDS_LIB pure_quanta
J 0
(-2750 700);
DISPLAY INVISIBLE (-2750 700);
FORCEPROP 0 LAST CDS_LOCATION C1363
J 0
(-2700 850);
DISPLAY 1.021277 (-2700 850);
DISPLAY INVISIBLE (-2700 850);
FORCEPROP 0 LAST $SEC 1
J 0
(-2700 850);
DISPLAY 0.680851 (-2700 850);
PAINT MONO (-2700 850);
DISPLAY INVISIBLE (-2700 850);
FORCEPROP 0 LAST CDS_SEC 1
J 0
(-2700 850);
DISPLAY 1.021277 (-2700 850);
DISPLAY INVISIBLE (-2700 850);
FORCEPROP 1 LAST PATH I5
J 0
(-2700 850);
DISPLAY 0.978723 (-2700 850);
PAINT WHITE (-2700 850);
DISPLAY INVISIBLE (-2700 850);
FORCEADD UNIVERSAL_POWER..1
(-2750 975);
FORCEPROP 3 LASTPIN (-2750 925) SIG_NAME PVNN_MAIN_CPU0\g
J 0
(-2740 935);
DISPLAY 0.659574 (-2740 935);
PAINT MONO (-2740 935);
DISPLAY INVISIBLE (-2740 935);
FORCEPROP 1 LAST HDL_POWER PVNN_MAIN_CPU0
J 1
(-2700 1025);
DISPLAY 1.085106 (-2700 1025);
PAINT GREEN (-2700 1025);
FORCEPROP 2 LAST CDS_LIB logical_power
J 0
(-2750 975);
DISPLAY INVISIBLE (-2750 975);
FORCEPROP 1 LAST PATH I6
J 0
(-2700 1000);
DISPLAY 0.872340 (-2700 1000);
PAINT AQUA (-2700 1000);
DISPLAY INVISIBLE (-2700 1000);
FORCEADD Q_RES..1
(-2375 -975);
FORCEPROP 1 LAST PART_NUMBER CS31002FB08
J 0
(-2500 -900);
DISPLAY 0.638298 (-2500 -900);
DISPLAY INVISIBLE (-2500 -900);
FORCEPROP 1 LAST TOLERANCE 1%
J 0
(-2125 -975);
DISPLAY 0.638298 (-2125 -975);
FORCEPROP 1 LAST VALUE 10K
J 2
(-2150 -975);
DISPLAY 0.638298 (-2150 -975);
FORCEPROP 1 LAST MATERIAL CHIP
J 0
(-2000 -975);
DISPLAY 0.638298 (-2000 -975);
FORCEPROP 1 LAST $LOCATION R320
J 0
(-2625 -975);
DISPLAY 0.787234 (-2625 -975);
FORCEPROP 1 LASTPIN (-2475 -975) $PN 1
J 0
(-2463 -963);
DISPLAY 0.787234 (-2463 -963);
FORCEPROP 1 LASTPIN (-2275 -975) $PN 2
J 0
(-2313 -963);
DISPLAY 0.787234 (-2313 -963);
FORCEPROP 2 LAST CDS_LIB pure_quanta
J 0
(-2375 -975);
PAINT MONO (-2375 -975);
DISPLAY INVISIBLE (-2375 -975);
FORCEPROP 1 LAST WATTAGE 1/16W
J 2
(-2150 -850);
DISPLAY 0.638298 (-2150 -850);
DISPLAY INVISIBLE (-2150 -850);
FORCEPROP 1 LAST PACK_TYPE 0402LF
J 0
(-2025 -975);
DISPLAY 0.638298 (-2025 -975);
DISPLAY INVISIBLE (-2025 -975);
FORCEPROP 2 LAST CDS_LOCATION R320
J 0
(-2425 -775);
DISPLAY 1.021277 (-2425 -775);
DISPLAY INVISIBLE (-2425 -775);
FORCEPROP 2 LAST $SEC 1
J 0
(-2425 -775);
DISPLAY 0.680851 (-2425 -775);
PAINT MONO (-2425 -775);
DISPLAY INVISIBLE (-2425 -775);
FORCEPROP 2 LAST CDS_SEC 1
J 0
(-2425 -775);
DISPLAY 1.021277 (-2425 -775);
DISPLAY INVISIBLE (-2425 -775);
FORCEPROP 1 LAST PATH I7
J 0
(-2425 -825);
DISPLAY 0.978723 (-2425 -825);
PAINT WHITE (-2425 -825);
DISPLAY INVISIBLE (-2425 -825);
FORCEADD Q_RES..1
(-2375 -850);
FORCEPROP 1 LAST PART_NUMBER CS31002FB08
J 0
(-2500 -775);
DISPLAY 0.638298 (-2500 -775);
DISPLAY INVISIBLE (-2500 -775);
FORCEPROP 1 LAST TOLERANCE 1%
J 0
(-2125 -850);
DISPLAY 0.638298 (-2125 -850);
FORCEPROP 1 LAST VALUE 10K
J 2
(-2150 -850);
DISPLAY 0.638298 (-2150 -850);
FORCEPROP 1 LAST PACK_TYPE 0402LF
J 0
(-2500 -725);
DISPLAY 0.638298 (-2500 -725);
FORCEPROP 1 LAST WATTAGE 1/16W
J 2
(-2150 -725);
DISPLAY 0.638298 (-2150 -725);
FORCEPROP 1 LAST MATERIAL CHIP
J 0
(-2000 -850);
DISPLAY 0.638298 (-2000 -850);
FORCEPROP 1 LAST $LOCATION R319
J 0
(-2625 -850);
DISPLAY 0.787234 (-2625 -850);
FORCEPROP 1 LASTPIN (-2475 -850) $PN 1
J 0
(-2463 -838);
DISPLAY 0.787234 (-2463 -838);
FORCEPROP 1 LASTPIN (-2275 -850) $PN 2
J 0
(-2313 -838);
DISPLAY 0.787234 (-2313 -838);
FORCEPROP 2 LAST CDS_LIB pure_quanta
J 0
(-2375 -850);
PAINT MONO (-2375 -850);
DISPLAY INVISIBLE (-2375 -850);
FORCEPROP 2 LAST CDS_LOCATION R319
J 0
(-2425 -650);
DISPLAY 1.021277 (-2425 -650);
DISPLAY INVISIBLE (-2425 -650);
FORCEPROP 2 LAST $SEC 1
J 0
(-2425 -650);
DISPLAY 0.680851 (-2425 -650);
PAINT MONO (-2425 -650);
DISPLAY INVISIBLE (-2425 -650);
FORCEPROP 2 LAST CDS_SEC 1
J 0
(-2425 -650);
DISPLAY 1.021277 (-2425 -650);
DISPLAY INVISIBLE (-2425 -650);
FORCEPROP 1 LAST PATH I8
J 0
(-2425 -700);
DISPLAY 0.978723 (-2425 -700);
PAINT WHITE (-2425 -700);
DISPLAY INVISIBLE (-2425 -700);
FORCEADD Q_CAP..1
(-2375 700);
FORCEPROP 1 LAST PART_NUMBER CH622KMEB01
J 0
(-2325 550);
DISPLAY 0.638298 (-2325 550);
DISPLAY INVISIBLE (-2325 550);
FORCEPROP 1 LAST VOLTAGE 4V
J 0
(-2325 700);
DISPLAY 0.638298 (-2325 700);
FORCEPROP 1 LAST PACK_TYPE C0402
J 0
(-2325 500);
DISPLAY 0.638298 (-2325 500);
FORCEPROP 1 LAST TOLERANCE 20%
J 0
(-2325 650);
DISPLAY 0.638298 (-2325 650);
FORCEPROP 1 LAST VALUE 22UF
J 0
(-2325 750);
DISPLAY 0.638298 (-2325 750);
FORCEPROP 1 LAST MATERIAL X6S
J 0
(-2325 600);
DISPLAY 0.638298 (-2325 600);
FORCEPROP 1 LAST $LOCATION C1364
J 0
(-2325 800);
DISPLAY 0.787234 (-2325 800);
FORCEPROP 1 LASTPIN (-2375 800) $PN 1
J 0
(-2365 780);
DISPLAY 0.787234 (-2365 780);
PAINT MONO (-2365 780);
FORCEPROP 1 LASTPIN (-2375 600) $PN 2
J 0
(-2365 580);
DISPLAY 0.787234 (-2365 580);
PAINT MONO (-2365 580);
FORCEPROP 2 LAST CDS_LIB pure_quanta
J 0
(-2375 700);
DISPLAY INVISIBLE (-2375 700);
FORCEPROP 0 LAST CDS_LOCATION C1364
J 0
(-2325 850);
DISPLAY 1.021277 (-2325 850);
DISPLAY INVISIBLE (-2325 850);
FORCEPROP 0 LAST $SEC 1
J 0
(-2325 850);
DISPLAY 0.680851 (-2325 850);
PAINT MONO (-2325 850);
DISPLAY INVISIBLE (-2325 850);
FORCEPROP 0 LAST CDS_SEC 1
J 0
(-2325 850);
DISPLAY 1.021277 (-2325 850);
DISPLAY INVISIBLE (-2325 850);
FORCEPROP 1 LAST PATH I9
J 0
(-2325 850);
DISPLAY 0.978723 (-2325 850);
PAINT WHITE (-2325 850);
DISPLAY INVISIBLE (-2325 850);
FORCEADD DNS..2
(-1770 1745);
PAINT RED (-1770 1745);
FORCEPROP 2 LAST CDS_LIB mstr_misc
J 0
(-1770 1745);
PAINT MONO (-1770 1745);
DISPLAY INVISIBLE (-1770 1745);
FORCEPROP 1 LAST COMMENT_BODY TRUE
J 0
(-1770 1745);
DISPLAY INVISIBLE (-1770 1745);
FORCEADD DNS..2
(1375 1750);
PAINT RED (1375 1750);
FORCEPROP 2 LAST CDS_LIB mstr_misc
J 0
(1375 1750);
PAINT MONO (1375 1750);
DISPLAY INVISIBLE (1375 1750);
FORCEPROP 1 LAST COMMENT_BODY TRUE
J 0
(1375 1750);
DISPLAY INVISIBLE (1375 1750);
FORCEADD QUANTA_TITLE_BLOCK_C..1
(4675 -3250);
FORCEPROP 0 LAST CDS_CON_LAST_MODIFIED Fri Aug 25 14:00:59 2023
J 0
(2790 -3235);
PAINT MONO (2790 -3235);
DISPLAY INVISIBLE (2790 -3235);
FORCEPROP 2 LAST CUSTOM_TXT_CDS <XR_PAGE_TITLE>
J 0
(-3215 2000);
DISPLAY 0.638298 (-3215 2000);
PAINT PINK (-3215 2000);
DISPLAY INVISIBLE (-3215 2000);
FORCEPROP 2 LAST CUSTOM_TXT_CDS <CON_PAGE_NUM> OF <CON_TOTAL_PAGES>
J 0
(4229 -3232);
DISPLAY 0.978723 (4229 -3232);
FORCEPROP 2 LAST CUSTOM_TXT_CDS <Q_REV>
J 0
(4491 -3147);
DISPLAY 1.212766 (4491 -3147);
FORCEPROP 2 LAST CUSTOM_TXT_CDS <Q_PROJ>
J 0
(2293 -3148);
DISPLAY 1.212766 (2293 -3148);
FORCEPROP 2 LAST CUSTOM_TXT_CDS <Q_NUMBER>
J 0
(3272 -3147);
DISPLAY 1.212766 (3272 -3147);
FORCEPROP 2 LAST CUSTOM_TXT_CDS <NAME_1>
J 0
(1500 -3075);
FORCEPROP 2 LAST CUSTOM_TXT_CDS <NAME_2>
J 0
(1500 -3200);
FORCEPROP 2 LAST CUSTOM_TXT_CDS <CON_LAST_MODIFIED>
J 0
(2790 -3235);
DISPLAY 0.978723 (2790 -3235);
FORCEPROP 1 LAST Q_TITLE SPR CPU0 & 1 - PVNN_TERM & MISC
J 0
(-4591 -3224);
DISPLAY 2.446809 (-4591 -3224);
PAINT GREEN (-4591 -3224);
FORCEPROP 1 LAST Q_DEPT 
J 1
(912 -3201);
DISPLAY 1.957447 (912 -3201);
PAINT GREEN (912 -3201);
FORCEPROP 1 LAST COMMENT_BODY TRUE
J 0
(4687 -3263);
DISPLAY 0.978723 (4687 -3263);
PAINT GREEN (4687 -3263);
DISPLAY INVISIBLE (4687 -3263);
FORCEPROP 2 LAST CDS_XR_PAGE_TITLE CR-80 : @S9S_MB_2U_LIB.S9S_MB_2U(SCH_1):PAGE80
J 0
(-3215 2000);
DISPLAY 0.638298 (-3215 2000);
PAINT PINK (-3215 2000);
DISPLAY INVISIBLE (-3215 2000);
FORCEPROP 2 LAST PAGE_BORDER TRUE
J 0
(-3215 2000);
DISPLAY 0.638298 (-3215 2000);
PAINT PINK (-3215 2000);
DISPLAY INVISIBLE (-3215 2000);
FORCEPROP 1 LAST CDS_LMAN_SYM_OUTLINE -9475,6775,100,-125
J 0
(4675 -3250);
DISPLAY 0.468085 (4675 -3250);
PAINT GREEN (4675 -3250);
DISPLAY INVISIBLE (4675 -3250);
FORCEPROP 2 LAST CDS_LIB pure_quanta
J 0
(4675 -3250);
PAINT MONO (4675 -3250);
DISPLAY INVISIBLE (4675 -3250);
WIRE 16 -1 (-2725 -650)(-2725 -850);
WIRE 16 -1 (-2750 925)(-2750 900);
WIRE 16 -1 (-2725 1975)(-2725 1500);
WIRE 16 -1 (-2275 1875)(-2275 1750);
WIRE 16 -1 (425 -650)(425 -850);
WIRE 16 -1 (400 925)(400 900);
WIRE 16 -1 (-1175 1975)(-1175 1750);
WIRE 16 -1 (425 1975)(425 1500);
WIRE 16 -1 (875 1875)(875 1750);
WIRE 16 -1 (1975 1975)(1975 1750);
WIRE 16 -1 (-2750 425)(-2750 475);
WIRE 16 -1 (400 425)(400 475);
WIRE 16 -1 (1975 1500)(1450 1500);
WIRE 16 -1 (1450 1750)(1975 1750);
WIRE 16 -1 (1975 1750)(1975 1500);
WIRE 16 -1 (875 1750)(1250 1750);
WIRE 16 -1 (425 1500)(1250 1500);
WIRE 16 -1 (2550 -850)(875 -850);
FORCEPROP 2 LAST SIG_NAME PU_S3M_CPU1_CPLD_STATUS
J 0
(1459 -841);
DISPLAY 0.680851 (1459 -841);
PAINT WHITE (1459 -841);
WIRE 16 -1 (2550 -975)(875 -975);
FORCEPROP 2 LAST SIG_NAME PU_S3M_CPU1_CPLD_CONFD
J 0
(1459 -966);
DISPLAY 0.680851 (1459 -966);
PAINT WHITE (1459 -966);
WIRE 16 -1 (2550 -1100)(875 -1100);
FORCEPROP 2 LAST SIG_NAME FM_S3M_CPU1_CPLD_CONFIG_N
J 0
(1459 -1091);
DISPLAY 0.680851 (1459 -1091);
PAINT WHITE (1459 -1091);
WIRE 16 -1 (2550 -1225)(875 -1225);
FORCEPROP 2 LAST SIG_NAME FM_S3M_CPU1_CPLD_CRC_ERROR
J 0
(1459 -1216);
DISPLAY 0.680851 (1459 -1216);
PAINT WHITE (1459 -1216);
WIRE 16 -1 (400 475)(400 600);
WIRE 16 -1 (775 475)(400 475);
WIRE 16 -1 (775 600)(775 475);
WIRE 16 -1 (400 900)(400 800);
WIRE 16 -1 (775 900)(400 900);
WIRE 16 -1 (775 800)(775 900);
WIRE 16 -1 (425 -1225)(675 -1225);
WIRE 16 -1 (425 -1100)(425 -1225);
WIRE 16 -1 (425 -1100)(675 -1100);
WIRE 16 -1 (425 -975)(425 -1100);
WIRE 16 -1 (425 -975)(675 -975);
WIRE 16 -1 (425 -850)(425 -975);
WIRE 16 -1 (425 -850)(675 -850);
WIRE 16 -1 (-1175 1500)(-1700 1500);
WIRE 16 -1 (-1700 1750)(-1175 1750);
WIRE 16 -1 (-1175 1750)(-1175 1500);
WIRE 16 -1 (-600 -1225)(-2275 -1225);
FORCEPROP 2 LAST SIG_NAME FM_S3M_CPU0_CPLD_CRC_ERROR
J 0
(-1691 -1216);
DISPLAY 0.680851 (-1691 -1216);
PAINT WHITE (-1691 -1216);
WIRE 16 -1 (-600 -850)(-2275 -850);
FORCEPROP 2 LAST SIG_NAME PU_S3M_CPU0_CPLD_STATUS
J 0
(-1691 -841);
DISPLAY 0.680851 (-1691 -841);
PAINT WHITE (-1691 -841);
WIRE 16 -1 (-600 -975)(-2275 -975);
FORCEPROP 2 LAST SIG_NAME PU_S3M_CPU0_CPLD_CONFD
J 0
(-1691 -966);
DISPLAY 0.680851 (-1691 -966);
PAINT WHITE (-1691 -966);
WIRE 16 -1 (-600 -1100)(-2275 -1100);
FORCEPROP 2 LAST SIG_NAME FM_S3M_CPU0_CPLD_CONFIG_N
J 0
(-1691 -1091);
DISPLAY 0.680851 (-1691 -1091);
PAINT WHITE (-1691 -1091);
WIRE 16 -1 (-2275 1750)(-1900 1750);
WIRE 16 -1 (-2725 1500)(-1900 1500);
WIRE 16 -1 (-2750 475)(-2750 600);
WIRE 16 -1 (-2375 475)(-2750 475);
WIRE 16 -1 (-2375 600)(-2375 475);
WIRE 16 -1 (-2750 900)(-2750 800);
WIRE 16 -1 (-2375 900)(-2750 900);
WIRE 16 -1 (-2375 800)(-2375 900);
WIRE 16 -1 (-2725 -1225)(-2475 -1225);
WIRE 16 -1 (-2725 -1100)(-2725 -1225);
WIRE 16 -1 (-2725 -1100)(-2475 -1100);
WIRE 16 -1 (-2725 -975)(-2725 -1100);
WIRE 16 -1 (-2725 -975)(-2475 -975);
WIRE 16 -1 (-2725 -850)(-2725 -975);
WIRE 16 -1 (-2725 -850)(-2475 -850);
DOT 1 (-2725 -1100);
DOT 1 (-2725 -975);
DOT 1 (-2725 -850);
DOT 1 (-2750 475);
DOT 1 (-2750 900);
DOT 1 (425 -1100);
DOT 1 (425 -975);
DOT 1 (425 -850);
DOT 1 (400 475);
DOT 1 (400 900);
DOT 1 (-1175 1750);
DOT 1 (1975 1750);
QUIT
